(kicad_pcb
	(version 20260206)
	(generator "pcbnew")
	(generator_version "10.0")
	(general
		(thickness 1.6)
		(legacy_teardrops no)
	)
	(paper "A4")
	(title_block
		(title "v1-chassis-manager — T6M_CM_d_v01_1031_1645.brd")
		(comment 1 "Open CloudServer (Microsoft) / footprints 2425-2432 of 2512")
	)
	(layers
		(0 "F.Cu" signal "TOP")
		(4 "In1.Cu" signal "GND1")
		(6 "In2.Cu" signal "IN1")
		(8 "In3.Cu" signal "VCC1")
		(10 "In4.Cu" signal "VCC2")
		(12 "In5.Cu" signal "GND2")
		(14 "In6.Cu" signal "IN2")
		(16 "In7.Cu" signal "IN3")
		(18 "In8.Cu" signal "GND3")
		(2 "B.Cu" signal "BOTTOM")
		(9 "F.Adhes" user "F.Adhesive")
		(11 "B.Adhes" user "B.Adhesive")
		(13 "F.Paste" user "Package Geometry/Pastemask Top")
		(15 "B.Paste" user "Package Geometry/Pastemask Bottom")
		(5 "F.SilkS" user "Ref Des/Silkscreen Top")
		(7 "B.SilkS" user "Ref Des/Silkscreen Bottom")
		(1 "F.Mask" user "Board Geometry/Soldermask Top")
		(3 "B.Mask" user "Board Geometry/Soldermask Bottom")
		(17 "Dwgs.User" user "User.Drawings")
		(19 "Cmts.User" user "User.Comments")
		(21 "Eco1.User" user "User.Eco1")
		(23 "Eco2.User" user "User.Eco2")
		(25 "Edge.Cuts" user "Board Geometry/Outline")
		(27 "Margin" user)
		(31 "F.CrtYd" user "Package Geometry/Place Bound Top")
		(29 "B.CrtYd" user "Package Geometry/Place Bound Bottom")
		(35 "F.Fab" user "Ref Des/Assembly Top")
		(33 "B.Fab" user "Ref Des/Assembly Bottom")
	)
	(footprint ""
		(layer "B.Cu")
		(at 135.36676 -184.951624 -90)
		(property "Reference" "C719"
			(at -4.357624 1.758188 270)
			(unlocked yes)
			(layer "B.SilkS")
			(effects
				(font
					(size 0.7874 0.5842)
					(thickness 0.1524)
				)
				(justify left mirror)
			)
		)
		(property "Value" ""
			(at 0 0 90)
			(layer "B.Fab")
			(effects
				(font
					(size 1.27 1.27)
				)
				(justify mirror)
			)
		)
		(duplicate_pad_numbers_are_jumpers no)
		(fp_line
			(start -0.7874 0.4064)
			(end 0.7874 0.4064)
			(stroke
				(width 0.1524)
				(type default)
			)
			(layer "B.SilkS")
		)
		(fp_line
			(start 0.7874 0.4064)
			(end 0.7874 -0.4064)
			(stroke
				(width 0.1524)
				(type default)
			)
			(layer "B.SilkS")
		)
		(fp_line
			(start 0 0.381)
			(end 0 -0.381)
			(stroke
				(width 0.1524)
				(type default)
			)
			(layer "B.SilkS")
		)
		(fp_line
			(start -0.7874 -0.4064)
			(end -0.7874 0.4064)
			(stroke
				(width 0.1524)
				(type default)
			)
			(layer "B.SilkS")
		)
		(fp_line
			(start 0.7874 -0.4064)
			(end -0.7874 -0.4064)
			(stroke
				(width 0.1524)
				(type default)
			)
			(layer "B.SilkS")
		)
		(fp_poly
			(pts
				(xy 0.5334 0.254) (xy 0.635 0.254) (xy 0.635 0.2286) (xy 0.635 -0.254) (xy 0.5334 -0.254) (xy 0.5334 -0.2794)
				(xy -0.5334 -0.2794) (xy -0.5334 -0.254) (xy -0.635 -0.254) (xy -0.635 0.254) (xy -0.5334 0.254)
				(xy -0.5334 0.2794) (xy 0.508 0.2794) (xy 0.5334 0.2794)
			)
			(stroke
				(width 0)
				(type default)
			)
			(fill no)
			(layer "B.CrtYd")
		)
		(pad "1" smd rect
			(at -0.40005 0 90)
			(size 0.4572 0.508)
			(layers "B.Cu" "B.Mask" "B.Paste")
			(net "UART_T9_NODE1_RXD")
		)
		(pad "2" smd rect
			(at 0.40005 0 90)
			(size 0.4572 0.508)
			(layers "B.Cu" "B.Mask" "B.Paste")
			(net "GND")
		)
	)
	(footprint ""
		(layer "B.Cu")
		(at 158.485078 -181.995318 90)
		(property "Reference" "R1175"
			(at -0.921258 3.197352 270)
			(unlocked yes)
			(layer "B.SilkS")
			(effects
				(font
					(size 0.7874 0.5842)
					(thickness 0.1524)
				)
				(justify left mirror)
			)
		)
		(property "Value" ""
			(at 0 0 90)
			(layer "B.Fab")
			(effects
				(font
					(size 1.27 1.27)
				)
				(justify mirror)
			)
		)
		(duplicate_pad_numbers_are_jumpers no)
		(fp_line
			(start 0.7874 -0.4064)
			(end -0.7874 -0.4064)
			(stroke
				(width 0.1524)
				(type default)
			)
			(layer "B.SilkS")
		)
		(fp_line
			(start -0.7874 -0.4064)
			(end -0.7874 0.4064)
			(stroke
				(width 0.1524)
				(type default)
			)
			(layer "B.SilkS")
		)
		(fp_line
			(start 0.7874 0.4064)
			(end 0.7874 -0.4064)
			(stroke
				(width 0.1524)
				(type default)
			)
			(layer "B.SilkS")
		)
		(fp_line
			(start -0.7874 0.4064)
			(end 0.7874 0.4064)
			(stroke
				(width 0.1524)
				(type default)
			)
			(layer "B.SilkS")
		)
		(fp_poly
			(pts
				(xy 0.508 0.2794) (xy 0.508 0.2286) (xy 0.635 0.2286) (xy 0.635 -0.254) (xy 0.5334 -0.254) (xy 0.5334 -0.2794)
				(xy -0.5334 -0.2794) (xy -0.5334 -0.254) (xy -0.635 -0.254) (xy -0.635 0.254) (xy -0.5334 0.254)
				(xy -0.5334 0.2794)
			)
			(stroke
				(width 0)
				(type default)
			)
			(fill no)
			(layer "B.CrtYd")
		)
		(pad "1" smd rect
			(at -0.40005 0 270)
			(size 0.4572 0.508)
			(layers "B.Cu" "B.Mask" "B.Paste")
			(net "CPLD_UART_RTS_P4_R_N")
		)
		(pad "2" smd rect
			(at 0.40005 0 270)
			(size 0.4572 0.508)
			(layers "B.Cu" "B.Mask" "B.Paste")
			(net "CPLD_UART_RTS_P4_N")
		)
	)
	(footprint ""
		(layer "B.Cu")
		(at 162.57778 -157.795722 -90)
		(property "Reference" "C465"
			(at -2.314448 0.620776 270)
			(unlocked yes)
			(layer "B.SilkS")
			(effects
				(font
					(size 0.7874 0.5842)
					(thickness 0.1524)
				)
				(justify left mirror)
			)
		)
		(property "Value" ""
			(at 0 0 90)
			(layer "B.Fab")
			(effects
				(font
					(size 1.27 1.27)
				)
				(justify mirror)
			)
		)
		(duplicate_pad_numbers_are_jumpers no)
		(fp_line
			(start -0.7874 0.4064)
			(end 0.7874 0.4064)
			(stroke
				(width 0.1524)
				(type default)
			)
			(layer "B.SilkS")
		)
		(fp_line
			(start 0.7874 0.4064)
			(end 0.7874 -0.4064)
			(stroke
				(width 0.1524)
				(type default)
			)
			(layer "B.SilkS")
		)
		(fp_line
			(start 0 0.381)
			(end 0 -0.381)
			(stroke
				(width 0.1524)
				(type default)
			)
			(layer "B.SilkS")
		)
		(fp_line
			(start -0.7874 -0.4064)
			(end -0.7874 0.4064)
			(stroke
				(width 0.1524)
				(type default)
			)
			(layer "B.SilkS")
		)
		(fp_line
			(start 0.7874 -0.4064)
			(end -0.7874 -0.4064)
			(stroke
				(width 0.1524)
				(type default)
			)
			(layer "B.SilkS")
		)
		(fp_poly
			(pts
				(xy 0.5334 0.254) (xy 0.635 0.254) (xy 0.635 0.2286) (xy 0.635 -0.254) (xy 0.5334 -0.254) (xy 0.5334 -0.2794)
				(xy -0.5334 -0.2794) (xy -0.5334 -0.254) (xy -0.635 -0.254) (xy -0.635 0.254) (xy -0.5334 0.254)
				(xy -0.5334 0.2794) (xy 0.508 0.2794) (xy 0.5334 0.2794)
			)
			(stroke
				(width 0)
				(type default)
			)
			(fill no)
			(layer "B.CrtYd")
		)
		(pad "1" smd rect
			(at -0.40005 0 90)
			(size 0.4572 0.508)
			(layers "B.Cu" "B.Mask" "B.Paste")
			(net "P1V05_LAN2")
		)
		(pad "2" smd rect
			(at 0.40005 0 90)
			(size 0.4572 0.508)
			(layers "B.Cu" "B.Mask" "B.Paste")
			(net "GND")
		)
	)
	(footprint ""
		(layer "B.Cu")
		(at 63.936118 -85.90915 90)
		(property "Reference" "C74"
			(at 1.344422 1.12649 270)
			(unlocked yes)
			(layer "B.SilkS")
			(effects
				(font
					(size 0.7874 0.5842)
					(thickness 0.1524)
				)
				(justify mirror)
			)
		)
		(property "Value" ""
			(at 0 0 90)
			(layer "B.Fab")
			(effects
				(font
					(size 1.27 1.27)
				)
				(justify mirror)
			)
		)
		(duplicate_pad_numbers_are_jumpers no)
		(fp_line
			(start 1.2954 -0.5842)
			(end -1.2954 -0.5842)
			(stroke
				(width 0.1524)
				(type default)
			)
			(layer "B.SilkS")
		)
		(fp_line
			(start 0 -0.5842)
			(end 0 0.5842)
			(stroke
				(width 0.1524)
				(type default)
			)
			(layer "B.SilkS")
		)
		(fp_line
			(start -1.2954 -0.5842)
			(end -1.2954 0.5842)
			(stroke
				(width 0.1524)
				(type default)
			)
			(layer "B.SilkS")
		)
		(fp_line
			(start 1.2954 0.5842)
			(end 1.2954 -0.5842)
			(stroke
				(width 0.1524)
				(type default)
			)
			(layer "B.SilkS")
		)
		(fp_line
			(start -1.2954 0.5842)
			(end 1.2954 0.5842)
			(stroke
				(width 0.1524)
				(type default)
			)
			(layer "B.SilkS")
		)
		(fp_poly
			(pts
				(xy -0.8636 -0.4572) (xy -0.8636 -0.3556) (xy -1.143 -0.3556) (xy -1.143 0.3556) (xy -0.8636 0.3556)
				(xy -0.8636 0.4572) (xy 0.8636 0.4572) (xy 0.8636 0.3556) (xy 1.143 0.3556) (xy 1.143 -0.3556) (xy 0.8636 -0.3556)
				(xy 0.8636 -0.4572)
			)
			(stroke
				(width 0)
				(type default)
			)
			(fill no)
			(layer "B.CrtYd")
		)
		(fp_line
			(start 0.884936 -0.504952)
			(end -0.884936 -0.504952)
			(stroke
				(width 0.1)
				(type default)
			)
			(layer "B.Fab")
		)
		(fp_line
			(start -0.884936 -0.504952)
			(end -0.884936 0.504952)
			(stroke
				(width 0.1)
				(type default)
			)
			(layer "B.Fab")
		)
		(fp_line
			(start 0.884936 0.504952)
			(end 0.884936 -0.504952)
			(stroke
				(width 0.1)
				(type default)
			)
			(layer "B.Fab")
		)
		(fp_line
			(start -0.884936 0.504952)
			(end 0.884936 0.504952)
			(stroke
				(width 0.1)
				(type default)
			)
			(layer "B.Fab")
		)
		(pad "1" smd rect
			(at -0.7366 0 180)
			(size 0.7112 0.8128)
			(layers "B.Cu" "B.Mask" "B.Paste")
			(net "P1V8_SUS_NODE1")
		)
		(pad "2" smd rect
			(at 0.7366 0 180)
			(size 0.7112 0.8128)
			(layers "B.Cu" "B.Mask" "B.Paste")
			(net "GND")
		)
	)
	(footprint ""
		(layer "B.Cu")
		(at 42.551858 -73.494138 180)
		(property "Reference" "R38"
			(at 0.957326 -1.619504 0)
			(unlocked yes)
			(layer "B.SilkS")
			(effects
				(font
					(size 0.7874 0.5842)
					(thickness 0.1524)
				)
				(justify left mirror)
			)
		)
		(property "Value" ""
			(at 0 0 0)
			(layer "B.Fab")
			(effects
				(font
					(size 1.27 1.27)
				)
				(justify mirror)
			)
		)
		(duplicate_pad_numbers_are_jumpers no)
		(fp_line
			(start 0.7874 0.4064)
			(end 0.7874 -0.4064)
			(stroke
				(width 0.1524)
				(type default)
			)
			(layer "B.SilkS")
		)
		(fp_line
			(start 0.7874 -0.4064)
			(end -0.7874 -0.4064)
			(stroke
				(width 0.1524)
				(type default)
			)
			(layer "B.SilkS")
		)
		(fp_line
			(start -0.7874 0.4064)
			(end 0.7874 0.4064)
			(stroke
				(width 0.1524)
				(type default)
			)
			(layer "B.SilkS")
		)
		(fp_line
			(start -0.7874 -0.4064)
			(end -0.7874 0.4064)
			(stroke
				(width 0.1524)
				(type default)
			)
			(layer "B.SilkS")
		)
		(fp_poly
			(pts
				(xy 0.508 0.2794) (xy 0.508 0.2286) (xy 0.635 0.2286) (xy 0.635 -0.254) (xy 0.5334 -0.254) (xy 0.5334 -0.2794)
				(xy -0.5334 -0.2794) (xy -0.5334 -0.254) (xy -0.635 -0.254) (xy -0.635 0.254) (xy -0.5334 0.254)
				(xy -0.5334 0.2794)
			)
			(stroke
				(width 0)
				(type default)
			)
			(fill no)
			(layer "B.CrtYd")
		)
		(pad "1" smd rect
			(at -0.40005 0)
			(size 0.4572 0.508)
			(layers "B.Cu" "B.Mask" "B.Paste")
			(net "PD_CPU_NODE1_AL5")
		)
		(pad "2" smd rect
			(at 0.40005 0)
			(size 0.4572 0.508)
			(layers "B.Cu" "B.Mask" "B.Paste")
			(net "GND")
		)
	)
	(footprint ""
		(layer "B.Cu")
		(at 30.16377 -104.991662 90)
		(property "Reference" "C818"
			(at -0.009652 -3.212592 270)
			(unlocked yes)
			(layer "B.SilkS")
			(effects
				(font
					(size 0.7874 0.5842)
					(thickness 0.1524)
				)
				(justify left mirror)
			)
		)
		(property "Value" ""
			(at 0 0 90)
			(layer "B.Fab")
			(effects
				(font
					(size 1.27 1.27)
				)
				(justify mirror)
			)
		)
		(duplicate_pad_numbers_are_jumpers no)
		(fp_line
			(start 1.905 -0.8636)
			(end -1.905 -0.8636)
			(stroke
				(width 0.1524)
				(type default)
			)
			(layer "B.SilkS")
		)
		(fp_line
			(start -1.905 -0.8636)
			(end -1.905 0.8636)
			(stroke
				(width 0.1524)
				(type default)
			)
			(layer "B.SilkS")
		)
		(fp_line
			(start 0 0.8382)
			(end 0 -0.8382)
			(stroke
				(width 0.1524)
				(type default)
			)
			(layer "B.SilkS")
		)
		(fp_line
			(start 1.905 0.8636)
			(end 1.905 -0.8636)
			(stroke
				(width 0.1524)
				(type default)
			)
			(layer "B.SilkS")
		)
		(fp_line
			(start -1.905 0.8636)
			(end 1.905 0.8636)
			(stroke
				(width 0.1524)
				(type default)
			)
			(layer "B.SilkS")
		)
		(fp_rect
			(start 1.524 0.7366)
			(end -1.524 -0.7366)
			(stroke
				(width 0)
				(type default)
			)
			(fill no)
			(layer "B.CrtYd")
		)
		(pad "1" smd rect
			(at -0.94996 0 270)
			(size 1.1176 1.3716)
			(layers "B.Cu" "B.Mask" "B.Paste")
			(net "P1V8_STB_NODE1")
		)
		(pad "2" smd rect
			(at 0.94996 0 270)
			(size 1.1176 1.3716)
			(layers "B.Cu" "B.Mask" "B.Paste")
			(net "GND")
		)
	)
	(footprint ""
		(layer "B.Cu")
		(at 55.22976 -176.315624 90)
		(property "Reference" "U63"
			(at -4.683252 4.289552 0)
			(unlocked yes)
			(layer "B.SilkS")
			(effects
				(font
					(size 0.7874 0.5842)
					(thickness 0.1524)
				)
				(justify left mirror)
			)
		)
		(property "Value" ""
			(at 0 0 90)
			(layer "B.Fab")
			(effects
				(font
					(size 1.27 1.27)
				)
				(justify mirror)
			)
		)
		(duplicate_pad_numbers_are_jumpers no)
		(fp_line
			(start 3.9624 -2.0066)
			(end -3.9624 -2.0066)
			(stroke
				(width 0.1524)
				(type default)
			)
			(layer "B.SilkS")
		)
		(fp_line
			(start -3.9624 -2.0066)
			(end -3.9624 2.0066)
			(stroke
				(width 0.1524)
				(type default)
			)
			(layer "B.SilkS")
		)
		(fp_line
			(start 3.9624 -0.5842)
			(end 3.9624 -2.0066)
			(stroke
				(width 0.1524)
				(type default)
			)
			(layer "B.SilkS")
		)
		(fp_line
			(start 3.3782 0)
			(end 3.9624 -0.5842)
			(stroke
				(width 0.1524)
				(type default)
			)
			(layer "B.SilkS")
		)
		(fp_line
			(start 3.9624 0.5842)
			(end 3.3782 0)
			(stroke
				(width 0.1524)
				(type default)
			)
			(layer "B.SilkS")
		)
		(fp_line
			(start 3.9624 2.0066)
			(end 3.9624 0.5842)
			(stroke
				(width 0.1524)
				(type default)
			)
			(layer "B.SilkS")
		)
		(fp_line
			(start -3.9624 2.0066)
			(end 3.9624 2.0066)
			(stroke
				(width 0.1524)
				(type default)
			)
			(layer "B.SilkS")
		)
		(fp_circle
			(center 3.429 1.524)
			(end 3.429 1.778)
			(stroke
				(width 0.1524)
				(type default)
			)
			(fill no)
			(layer "B.SilkS")
		)
		(fp_poly
			(pts
				(xy 3.962654 3.6703) (xy 3.974846 -3.6703) (xy -3.9624 -3.6703) (xy -3.9624 3.6703)
			)
			(stroke
				(width 0)
				(type default)
			)
			(fill no)
			(layer "B.CrtYd")
		)
		(pad "1" smd rect
			(at 3.57505 2.921 270)
			(size 0.3556 1.4986)
			(layers "B.Cu" "B.Mask" "B.Paste")
			(net "PCA9535_INT_N")
		)
		(pad "2" smd rect
			(at 2.925064 2.921 270)
			(size 0.3556 1.4986)
			(layers "B.Cu" "B.Mask" "B.Paste")
			(net "N21699710")
		)
		(pad "3" smd rect
			(at 2.275078 2.921 270)
			(size 0.3556 1.4986)
			(layers "B.Cu" "B.Mask" "B.Paste")
			(net "N21700864")
		)
		(pad "4" smd rect
			(at 1.625092 2.921 270)
			(size 0.3556 1.4986)
			(layers "B.Cu" "B.Mask" "B.Paste")
			(net "PSU1_AC_OK")
		)
		(pad "5" smd rect
			(at 0.975106 2.921 270)
			(size 0.3556 1.4986)
			(layers "B.Cu" "B.Mask" "B.Paste")
			(net "PSU2_AC_OK")
		)
		(pad "6" smd rect
			(at 0.32512 2.921 270)
			(size 0.3556 1.4986)
			(layers "B.Cu" "B.Mask" "B.Paste")
			(net "PSU3_AC_OK")
		)
		(pad "7" smd rect
			(at -0.32512 2.921 270)
			(size 0.3556 1.4986)
			(layers "B.Cu" "B.Mask" "B.Paste")
			(net "PSU4_AC_OK")
		)
		(pad "8" smd rect
			(at -0.975106 2.921 270)
			(size 0.3556 1.4986)
			(layers "B.Cu" "B.Mask" "B.Paste")
			(net "PSU5_AC_OK")
		)
		(pad "9" smd rect
			(at -1.625092 2.921 270)
			(size 0.3556 1.4986)
			(layers "B.Cu" "B.Mask" "B.Paste")
			(net "PSU6_AC_OK")
		)
		(pad "10" smd rect
			(at -2.275078 2.921 270)
			(size 0.3556 1.4986)
			(layers "B.Cu" "B.Mask" "B.Paste")
			(net "PSU1_DC_OK")
		)
		(pad "11" smd rect
			(at -2.925064 2.921 270)
			(size 0.3556 1.4986)
			(layers "B.Cu" "B.Mask" "B.Paste")
			(net "PSU2_DC_OK")
		)
		(pad "12" smd rect
			(at -3.57505 2.921 270)
			(size 0.3556 1.4986)
			(layers "B.Cu" "B.Mask" "B.Paste")
			(net "GND")
		)
		(pad "13" smd rect
			(at -3.57505 -2.921 270)
			(size 0.3556 1.4986)
			(layers "B.Cu" "B.Mask" "B.Paste")
			(net "PSU3_DC_OK")
		)
		(pad "14" smd rect
			(at -2.925064 -2.921 270)
			(size 0.3556 1.4986)
			(layers "B.Cu" "B.Mask" "B.Paste")
			(net "PSU4_DC_OK")
		)
		(pad "15" smd rect
			(at -2.275078 -2.921 270)
			(size 0.3556 1.4986)
			(layers "B.Cu" "B.Mask" "B.Paste")
			(net "PSU5_DC_OK")
		)
		(pad "16" smd rect
			(at -1.625092 -2.921 270)
			(size 0.3556 1.4986)
			(layers "B.Cu" "B.Mask" "B.Paste")
			(net "PSU6_DC_OK")
		)
		(pad "17" smd rect
			(at -0.975106 -2.921 270)
			(size 0.3556 1.4986)
			(layers "B.Cu" "B.Mask" "B.Paste")
			(net "PSU_ALERT_N")
		)
		(pad "18" smd rect
			(at -0.32512 -2.921 270)
			(size 0.3556 1.4986)
			(layers "B.Cu" "B.Mask" "B.Paste")
			(net "Net_48")
		)
		(pad "19" smd rect
			(at 0.32512 -2.921 270)
			(size 0.3556 1.4986)
			(layers "B.Cu" "B.Mask" "B.Paste")
			(net "CPLD_THRMTRIP_LOG_N")
		)
		(pad "20" smd rect
			(at 0.975106 -2.921 270)
			(size 0.3556 1.4986)
			(layers "B.Cu" "B.Mask" "B.Paste")
			(net "Net_294")
		)
		(pad "21" smd rect
			(at 1.625092 -2.921 270)
			(size 0.3556 1.4986)
			(layers "B.Cu" "B.Mask" "B.Paste")
			(net "N21699710")
		)
		(pad "22" smd rect
			(at 2.275078 -2.921 270)
			(size 0.3556 1.4986)
			(layers "B.Cu" "B.Mask" "B.Paste")
			(net "I2C_COM3_SCL")
		)
		(pad "23" smd rect
			(at 2.925064 -2.921 270)
			(size 0.3556 1.4986)
			(layers "B.Cu" "B.Mask" "B.Paste")
			(net "I2C_COM3_SDA")
		)
		(pad "24" smd rect
			(at 3.57505 -2.921 270)
			(size 0.3556 1.4986)
			(layers "B.Cu" "B.Mask" "B.Paste")
			(net "P3V3_NODE1")
		)
	)
	(footprint ""
		(layer "B.Cu")
		(at 70.665086 -131.153662 90)
		(property "Reference" "C279"
			(at -55.911242 -38.443916 270)
			(unlocked yes)
			(layer "B.SilkS")
			(effects
				(font
					(size 0.7874 0.5842)
					(thickness 0.1524)
				)
				(justify left mirror)
			)
		)
		(property "Value" ""
			(at 0 0 90)
			(layer "B.Fab")
			(effects
				(font
					(size 1.27 1.27)
				)
				(justify mirror)
			)
		)
		(duplicate_pad_numbers_are_jumpers no)
		(fp_line
			(start 0.7874 -0.4064)
			(end -0.7874 -0.4064)
			(stroke
				(width 0.1524)
				(type default)
			)
			(layer "B.SilkS")
		)
		(fp_line
			(start -0.7874 -0.4064)
			(end -0.7874 0.4064)
			(stroke
				(width 0.1524)
				(type default)
			)
			(layer "B.SilkS")
		)
		(fp_line
			(start 0 0.381)
			(end 0 -0.381)
			(stroke
				(width 0.1524)
				(type default)
			)
			(layer "B.SilkS")
		)
		(fp_line
			(start 0.7874 0.4064)
			(end 0.7874 -0.4064)
			(stroke
				(width 0.1524)
				(type default)
			)
			(layer "B.SilkS")
		)
		(fp_line
			(start -0.7874 0.4064)
			(end 0.7874 0.4064)
			(stroke
				(width 0.1524)
				(type default)
			)
			(layer "B.SilkS")
		)
		(fp_poly
			(pts
				(xy 0.5334 0.254) (xy 0.635 0.254) (xy 0.635 0.2286) (xy 0.635 -0.254) (xy 0.5334 -0.254) (xy 0.5334 -0.2794)
				(xy -0.5334 -0.2794) (xy -0.5334 -0.254) (xy -0.635 -0.254) (xy -0.635 0.254) (xy -0.5334 0.254)
				(xy -0.5334 0.2794) (xy 0.508 0.2794) (xy 0.5334 0.2794)
			)
			(stroke
				(width 0)
				(type default)
			)
			(fill no)
			(layer "B.CrtYd")
		)
		(pad "1" smd rect
			(at -0.40005 0 270)
			(size 0.4572 0.508)
			(layers "B.Cu" "B.Mask" "B.Paste")
			(net "P3V3_NODE1")
		)
		(pad "2" smd rect
			(at 0.40005 0 270)
			(size 0.4572 0.508)
			(layers "B.Cu" "B.Mask" "B.Paste")
			(net "GND")
		)
	)
)
